# 2Slot_Riser card_6L_stackup.xlsx — 工作表2 (pcb-stackup)
|  |  |  |  |  |  | Version |  |  |  |  |  |  |  |  |  |  |  |  |  |  |  |  |  |  |  |  |
| Board Number: |  | 15968-1A |  |  |  | 04 |  |  |  |  |  |  |  |  |  |  |  |  |  |  |  |  |  |  |  |  |
| Project name: |  | Tioga Pass |  |  |  |  |  |  |  |  |  |  |  |  |  |  |  |  |  |  |  |  |  |  |  |  |
| Model Name: |  | PCIe Riser SS 2Slots |  |  |  |  |  |  |  |  |  |  |  |  |  |  |  |  |  |  |  |  |  |  |  |  |
| Layer Count: |  | 6 Layer |  |  |  |  |  |  |  |  |  |  |  |  |  |  |  |  |  |  |  |  |  |  |  |  |
| Date: |  | 2016-09-19 00:00:00 |  |  |  |  |  |  |  |  |  |  |  |  |  |  |  |  |  |  |  |  |  |  |  |  |
| Material: |  | TU747HF / IT150G / NPG150N |  |  |  |  |  |  |  | Single Ended Type(mil) |  |  |  |  | Differential Type(mil) |  |  |  |  |  |  |  |  |  |  |  |
| Golden Finger(Y/N): |  | Y |  |  |  |  |  |  | Imp | 50 |  |  |  | Imp | 85 |  |  |  |  |  | 90 |  |  |  |  |  |
| Customer: |  | XXXXX |  |  |  |  |  |  | Variation | Inner/Outer+/-5ohm |  |  |  | Variation | Inner/Outer+/-10% |  |  |  |  |  | Inner/Outer+/-10% |  |  |  |  |  |
| EE engineer |  | <name> |  |  |  |  |  |  | Bus | MISC./I2C |  |  |  | Bus | PCIe/Clock |  |  |  |  |  | USB |  |  |  |  |  |
| SI Engineer |  | <name> |  |  |  |  |  |  |  |  |  |  |  |  |  |  |  |  |  |  |  |  |  |  |  |  |
|  |  |  |  |  |  |  |  |  | Type | SE |  |  |  | Type | DP |  |  |  |  |  | DP |  |  |  |  |  |
| Layer |  |  | Thickness |  | Glass/Copper Style | Er |  | Df(1G) | Layers | 1,3,4,6 |  |  |  | Layers | 1,3,4,6 |  |  |  |  |  | 1,3,4,6 |  |  |  |  |  |
|  |  | Cu oz | Wiwynn |  |  | Wiwynn |  |  |  | Wiwynn |  |  |  |  | Wiwynn |  |  |  |  |  | Wiwynn |  |  |  |  |  |
|  | Mask |  | 0.5 |  |  | 3.4 |  |  |  | Width | Imp | Width | Imp |  | Width | Space | Imp | Width | Space | Imp | Width | Space | Imp | Width | Space | Imp |
| Top | Signal | 0.5 oz+plating | 1.9 |  |  |  |  |  | S1 | 4(L2) |  |  |  | S1 | 5(L2) | 7 |  |  |  |  | 4.5(L2) | 7 |  |  |  |  |
|  | Prepreg |  | 2.7 |  |  | 4 |  |  |  |  |  |  |  |  |  |  |  |  |  |  |  |  |  |  |  |  |
| L2 | GND | 1 oz | 1.3 |  |  |  |  |  | P2 | reference layer |  |  |  | P2 | reference layer |  |  |  |  |  | reference layer |  |  |  |  |  |
|  | Core |  | 4 |  |  | 4 |  |  |  |  |  |  |  |  |  |  |  |  |  |  |  |  |  |  |  |  |
| L3 | Signal | 1 oz | 1.3 |  |  |  |  |  | S3 | 5(L2/L5) |  |  |  | S3 | 5(L2/L5) | 6.5 |  |  |  |  | 5(L2/L5) | 9 |  |  |  |  |
|  | Prepreg |  | 38.6 |  |  | 4.5 |  |  |  |  |  |  |  |  |  |  |  |  |  |  |  |  |  |  |  |  |
| L4 | Signal | 1 oz | 1.3 | 0 | 0 |  |  |  | S4 | 5(L2/L5) |  |  |  | S4 | 5(L2/L5) | 6.5 |  |  |  |  | 5(L2/L5) | 9 |  |  |  |  |
|  | Core |  | 4 | 0 | 0 | 4 | 0 | 0 |  |  |  |  |  |  |  |  |  |  |  |  |  |  |  |  |  |  |
| L5 | GND | 1 oz | 1.3 | 0 | 0 |  |  |  | P5 | reference layer |  |  |  | P5 | reference layer |  |  |  |  |  | reference layer |  |  |  |  |  |
|  | Prepreg |  | 2.7 | 0 | 0 | 4 | 0 | 0 |  |  |  |  |  |  |  |  |  |  |  |  |  |  |  |  |  |  |
| Bottom | Signal | 0.5 oz+plating | 1.9 | 0 | 0 |  |  |  | S6 | 4(L5) |  |  |  | S6 | 5(L5) | 7 |  |  |  |  | 4.5(L5) | 7 |  |  |  |  |
|  | Mask |  | 0.5 | 0 |  | 3.4 | 0 | 0 |  |  |  |  |  |  |  |  |  |  |  |  |  |  |  |  |  |  |
| Thickness requirement: 1.57 ± 10% mm |  | mil | 61.99999999999999 |  |  |  |  |  |  |  |  |  |  |  |  |  |  |  |  |  |  |  |  |  |  |  |
|  |  | mm | 1.574803149606299 |  |  |  |  |  |  |  |  |  |  |  |  |  |  |  |  |  |  |  |  |  |  |  |
| Note: | 1. Unit is mil |  |  |  |  |  |  |  |  |  |  |  |  |  |  |  |  |  |  |  |  |  |  |  |  |  |
|  | 2. The total thickness includes trace and solder mask |  |  |  |  |  |  |  |  |  |  |  |  |  |  |  |  |  |  |  |  |  |  |  |  |  |
|  | 3. Min hole copper thickness is 1.0 mil |  |  |  |  |  |  |  |  |  |  |  |  |  |  |  |  |  |  |  |  |  |  |  |  |  |
|  | 4. Min surface copper thickness 1.5 mil |  |  |  |  |  |  |  |  |  |  |  |  |  |  |  |  |  |  |  |  |  |  |  |  |  |
|  | 5. Impedance Cpk requirement: >=1.33 (Report should be provided) |  |  |  |  |  |  |  |  |  |  |  |  |  |  |  |  |  |  |  |  |  |  |  |  |  |
|  | 6. PCB supplier should design Delta-L coupon and provide measurement results meeting following criteria: |  |  |  |  |  |  |  |  |  |  |  |  |  |  |  |  |  |  |  |  |  |  |  |  |  |
|  | 。  -0.75dB/inch at 4GHz for stripline routing |  |  |  |  |  |  |  |  |  |  |  |  |  |  |  |  |  |  |  |  |  |  |  |  |  |
|  | 。  -0.79dB/inch at 4GHz for microstrip routing |  |  |  |  |  |  |  |  |  |  |  |  |  |  |  |  |  |  |  |  |  |  |  |  |  |
